# S9S_MB_2U (Grand Teton) — schematic netlist excerpt (pin names and nets, part order shuffled) for the footprints in the layout excerpt that follows; sources: Cadence DE-HDL packaged netlist, KiCad conversion of 03242023_DA0F0TMBIJ0_F0T_Motherboard_J_brd_V01_OCP.brd

R1765  Q_RES  0 5% EMPTY  pkg 0805LF  page 257 : A = PGPPA_AUX ; B = P3V3_AUX
R2893  Q_RES  0 5% EMPTY  pkg 0402LF  page 234 : A = SMB_1_BMC_GPU_R_SCL ; B = SMB_1_BMC_GPU_BUF_R_SCL
C747  Q_CAP_DIFFBUS  DIFF BUS_0.22UF 6.3V 20% X6S  pkg C0201  page 176 : \1\ = P5E_CPU1_PE2_TX_C_DP<13> ; \2\ = P5E_CPU1_PE2_TX_DP<13>

(kicad_pcb
	(version 20260206)
	(generator "pcbnew")
	(generator_version "10.0")
	(general
		(thickness 1.6)
		(legacy_teardrops no)
	)
	(paper "A4")
	(title_block
		(title "03242023_DA0F0TMBIJ0_F0T_Motherboard_J_brd_V01_OCP.brd")
		(comment 1 "Grand Teton / footprints 951-953 of 6105")
	)
	(layers
		(0 "F.Cu" signal "TOP")
		(4 "In1.Cu" signal "GND")
		(6 "In2.Cu" signal "IN1")
		(8 "In3.Cu" signal "GND1")
		(10 "In4.Cu" signal "IN2")
		(12 "In5.Cu" signal "GND2")
		(14 "In6.Cu" signal "IN3")
		(16 "In7.Cu" signal "GND3")
		(18 "In8.Cu" signal "VCC")
		(20 "In9.Cu" signal "VCC1")
		(22 "In10.Cu" signal "GND4")
		(24 "In11.Cu" signal "IN4")
		(26 "In12.Cu" signal "GND5")
		(28 "In13.Cu" signal "IN5")
		(30 "In14.Cu" signal "GND6")
		(32 "In15.Cu" signal "IN6")
		(34 "In16.Cu" signal "GND7")
		(2 "B.Cu" signal "BOTTOM")
		(9 "F.Adhes" user "F.Adhesive")
		(11 "B.Adhes" user "B.Adhesive")
		(13 "F.Paste" user "Package Geometry/Pastemask Top")
		(15 "B.Paste" user "Package Geometry/Pastemask Bottom")
		(5 "F.SilkS" user "Ref Des/Silkscreen Top")
		(7 "B.SilkS" user "Ref Des/Silkscreen Bottom")
		(1 "F.Mask" user "Board Geometry/Soldermask Top")
		(3 "B.Mask" user "Board Geometry/Soldermask Bottom")
		(17 "Dwgs.User" user "User.Drawings")
		(19 "Cmts.User" user "User.Comments")
		(21 "Eco1.User" user "User.Eco1")
		(23 "Eco2.User" user "User.Eco2")
		(25 "Edge.Cuts" user "Board Geometry/Outline")
		(27 "Margin" user)
		(31 "F.CrtYd" user "Package Geometry/Place Bound Top")
		(29 "B.CrtYd" user "Package Geometry/Place Bound Bottom")
		(35 "F.Fab" user "Ref Des/Assembly Top")
		(33 "B.Fab" user "Ref Des/Assembly Bottom")
	)
	(footprint ""
		(layer "F.Cu")
		(at 40.161972 -434.344318 90)
		(property "Reference" "R2893"
			(at 0 0 90)
			(layer "F.SilkS")
			(hide yes)
			(effects
				(font
					(size 1.27 1.27)
				)
			)
		)
		(property "Value" ""
			(at 0 0 90)
			(layer "F.Fab")
			(effects
				(font
					(size 1.27 1.27)
				)
			)
		)
		(duplicate_pad_numbers_are_jumpers no)
		(fp_line
			(start 0.7874 -0.4064)
			(end 0.7874 0.4064)
			(stroke
				(width 0.1524)
				(type default)
			)
			(layer "F.SilkS")
		)
		(fp_line
			(start -0.7874 -0.4064)
			(end 0.7874 -0.4064)
			(stroke
				(width 0.1524)
				(type default)
			)
			(layer "F.SilkS")
		)
		(fp_line
			(start 0.7874 0.4064)
			(end -0.7874 0.4064)
			(stroke
				(width 0.1524)
				(type default)
			)
			(layer "F.SilkS")
		)
		(fp_line
			(start -0.7874 0.4064)
			(end -0.7874 -0.4064)
			(stroke
				(width 0.1524)
				(type default)
			)
			(layer "F.SilkS")
		)
		(fp_line
			(start -0.12065 -0.305054)
			(end -0.12065 -0.2794)
			(stroke
				(width 0.1)
				(type default)
			)
			(layer "F.Fab")
		)
		(fp_line
			(start -0.67945 -0.305054)
			(end -0.12065 -0.305054)
			(stroke
				(width 0.1)
				(type default)
			)
			(layer "F.Fab")
		)
		(fp_line
			(start 0.67945 -0.3048)
			(end 0.67945 0.3048)
			(stroke
				(width 0.1)
				(type default)
			)
			(layer "F.Fab")
		)
		(fp_line
			(start 0.12065 -0.3048)
			(end 0.67945 -0.3048)
			(stroke
				(width 0.1)
				(type default)
			)
			(layer "F.Fab")
		)
		(fp_line
			(start 0.12065 -0.2794)
			(end 0.12065 -0.3048)
			(stroke
				(width 0.1)
				(type default)
			)
			(layer "F.Fab")
		)
		(fp_line
			(start -0.12065 -0.2794)
			(end 0.12065 -0.2794)
			(stroke
				(width 0.1)
				(type default)
			)
			(layer "F.Fab")
		)
		(fp_line
			(start 0.120396 0.2794)
			(end -0.12065 0.2794)
			(stroke
				(width 0.1)
				(type default)
			)
			(layer "F.Fab")
		)
		(fp_line
			(start -0.12065 0.2794)
			(end -0.12065 0.3048)
			(stroke
				(width 0.1)
				(type default)
			)
			(layer "F.Fab")
		)
		(fp_line
			(start 0.67945 0.3048)
			(end 0.120396 0.3048)
			(stroke
				(width 0.1)
				(type default)
			)
			(layer "F.Fab")
		)
		(fp_line
			(start 0.120396 0.3048)
			(end 0.120396 0.2794)
			(stroke
				(width 0.1)
				(type default)
			)
			(layer "F.Fab")
		)
		(fp_line
			(start -0.12065 0.3048)
			(end -0.67945 0.3048)
			(stroke
				(width 0.1)
				(type default)
			)
			(layer "F.Fab")
		)
		(fp_line
			(start -0.67945 0.3048)
			(end -0.67945 -0.305054)
			(stroke
				(width 0.1)
				(type default)
			)
			(layer "F.Fab")
		)
		(pad "1" smd circle
			(at -0.40005 0 90)
			(size 0 0)
			(layers "F.Cu" "F.Mask" "F.Paste")
			(net "SMB_1_BMC_GPU_R_SCL")
		)
		(pad "2" smd circle
			(at 0.40005 0 90)
			(size 0 0)
			(layers "F.Cu" "F.Mask" "F.Paste")
			(net "SMB_1_BMC_GPU_BUF_R_SCL")
		)
	)
	(footprint ""
		(layer "F.Cu")
		(at 126.256034 -402.371052 -90)
		(property "Reference" "C747"
			(at 0 0 270)
			(layer "F.SilkS")
			(hide yes)
			(effects
				(font
					(size 1.27 1.27)
				)
			)
		)
		(property "Value" ""
			(at 0 0 270)
			(layer "F.Fab")
			(effects
				(font
					(size 1.27 1.27)
				)
			)
		)
		(duplicate_pad_numbers_are_jumpers no)
		(fp_line
			(start -0.299974 0.150114)
			(end -0.299974 -0.150114)
			(stroke
				(width 0.1)
				(type default)
			)
			(layer "F.Fab")
		)
		(fp_line
			(start 0.299974 0.150114)
			(end -0.299974 0.150114)
			(stroke
				(width 0.1)
				(type default)
			)
			(layer "F.Fab")
		)
		(fp_line
			(start -0.299974 -0.150114)
			(end 0.299974 -0.150114)
			(stroke
				(width 0.1)
				(type default)
			)
			(layer "F.Fab")
		)
		(fp_line
			(start 0.299974 -0.150114)
			(end 0.299974 0.150114)
			(stroke
				(width 0.1)
				(type default)
			)
			(layer "F.Fab")
		)
		(pad "1" smd rect
			(at -0.2667 0 270)
			(size 0.3048 0.381)
			(layers "F.Cu" "F.Mask" "F.Paste")
			(net "P5E_CPU1_PE2_TX_C_DP<13>")
		)
		(pad "2" smd rect
			(at 0.2667 0 270)
			(size 0.3048 0.381)
			(layers "F.Cu" "F.Mask" "F.Paste")
			(net "P5E_CPU1_PE2_TX_DP<13>")
		)
	)
	(footprint ""
		(layer "F.Cu")
		(at 322.287138 -13.721588 180)
		(property "Reference" "R1765"
			(at 0 0 180)
			(layer "F.SilkS")
			(hide yes)
			(effects
				(font
					(size 1.27 1.27)
				)
			)
		)
		(property "Value" ""
			(at 0 0 180)
			(layer "F.Fab")
			(effects
				(font
					(size 1.27 1.27)
				)
			)
		)
		(duplicate_pad_numbers_are_jumpers no)
		(fp_line
			(start 1.651 0.8382)
			(end -1.651 0.8382)
			(stroke
				(width 0.1524)
				(type default)
			)
			(layer "F.SilkS")
		)
		(fp_line
			(start 1.651 -0.8382)
			(end 1.651 0.8382)
			(stroke
				(width 0.1524)
				(type default)
			)
			(layer "F.SilkS")
		)
		(fp_line
			(start -1.651 0.8382)
			(end -1.651 -0.8382)
			(stroke
				(width 0.1524)
				(type default)
			)
			(layer "F.SilkS")
		)
		(fp_line
			(start -1.651 -0.8382)
			(end 1.651 -0.8382)
			(stroke
				(width 0.1524)
				(type default)
			)
			(layer "F.SilkS")
		)
		(fp_line
			(start 1.560576 0.7366)
			(end 1.560576 -0.7366)
			(stroke
				(width 0.1)
				(type default)
			)
			(layer "F.Fab")
		)
		(fp_line
			(start 1.560576 -0.7366)
			(end 1.524 -0.7366)
			(stroke
				(width 0.1)
				(type default)
			)
			(layer "F.Fab")
		)
		(fp_line
			(start 1.524 0.7366)
			(end 1.560576 0.7366)
			(stroke
				(width 0.1)
				(type default)
			)
			(layer "F.Fab")
		)
		(fp_line
			(start 1.524 -0.7366)
			(end -1.524 -0.7366)
			(stroke
				(width 0.1)
				(type default)
			)
			(layer "F.Fab")
		)
		(fp_line
			(start -1.524 0.7366)
			(end 1.524 0.7366)
			(stroke
				(width 0.1)
				(type default)
			)
			(layer "F.Fab")
		)
		(fp_line
			(start -1.524 -0.7366)
			(end -1.559814 -0.7366)
			(stroke
				(width 0.1)
				(type default)
			)
			(layer "F.Fab")
		)
		(fp_line
			(start -1.559814 0.7366)
			(end -1.524 0.7366)
			(stroke
				(width 0.1)
				(type default)
			)
			(layer "F.Fab")
		)
		(fp_line
			(start -1.559814 -0.7366)
			(end -1.559814 0.7366)
			(stroke
				(width 0.1)
				(type default)
			)
			(layer "F.Fab")
		)
		(pad "1" smd rect
			(at -0.94996 0)
			(size 1.1176 1.3716)
			(layers "F.Cu" "F.Mask" "F.Paste")
			(net "PGPPA_AUX")
		)
		(pad "2" smd rect
			(at 0.94996 0)
			(size 1.1176 1.3716)
			(layers "F.Cu" "F.Mask" "F.Paste")
			(net "P3V3_AUX")
		)
	)
)
